# S9S_MB_2U (Grand Teton) — schematic netlist excerpt (pin names and nets, part order shuffled) for the footprints in the layout excerpt that follows; sources: Cadence DE-HDL packaged netlist, KiCad conversion of 03242023_DA0F0TMBIJ0_F0T_Motherboard_J_brd_V01_OCP.brd

PR632  Q_RES  0 5% EMPTY  pkg 0402LF  page 271 : A = P3V3 ; B = PVCCFA_EHV_FIVRA_CPU0_PVCC1
PR3953  Q_RES  120K 1% CHIP  pkg 0402LF  page 193 : A = P12V_AUX ; B = P12V_E1S_OV_FB_0

(kicad_pcb
	(version 20260206)
	(generator "pcbnew")
	(generator_version "10.0")
	(general
		(thickness 1.6)
		(legacy_teardrops no)
	)
	(paper "A4")
	(title_block
		(title "03242023_DA0F0TMBIJ0_F0T_Motherboard_J_brd_V01_OCP.brd")
		(comment 1 "Grand Teton / footprints 2772-2773 of 6105")
	)
	(layers
		(0 "F.Cu" signal "TOP")
		(4 "In1.Cu" signal "GND")
		(6 "In2.Cu" signal "IN1")
		(8 "In3.Cu" signal "GND1")
		(10 "In4.Cu" signal "IN2")
		(12 "In5.Cu" signal "GND2")
		(14 "In6.Cu" signal "IN3")
		(16 "In7.Cu" signal "GND3")
		(18 "In8.Cu" signal "VCC")
		(20 "In9.Cu" signal "VCC1")
		(22 "In10.Cu" signal "GND4")
		(24 "In11.Cu" signal "IN4")
		(26 "In12.Cu" signal "GND5")
		(28 "In13.Cu" signal "IN5")
		(30 "In14.Cu" signal "GND6")
		(32 "In15.Cu" signal "IN6")
		(34 "In16.Cu" signal "GND7")
		(2 "B.Cu" signal "BOTTOM")
		(9 "F.Adhes" user "F.Adhesive")
		(11 "B.Adhes" user "B.Adhesive")
		(13 "F.Paste" user "Package Geometry/Pastemask Top")
		(15 "B.Paste" user "Package Geometry/Pastemask Bottom")
		(5 "F.SilkS" user "Ref Des/Silkscreen Top")
		(7 "B.SilkS" user "Ref Des/Silkscreen Bottom")
		(1 "F.Mask" user "Board Geometry/Soldermask Top")
		(3 "B.Mask" user "Board Geometry/Soldermask Bottom")
		(17 "Dwgs.User" user "User.Drawings")
		(19 "Cmts.User" user "User.Comments")
		(21 "Eco1.User" user "User.Eco1")
		(23 "Eco2.User" user "User.Eco2")
		(25 "Edge.Cuts" user "Board Geometry/Outline")
		(27 "Margin" user)
		(31 "F.CrtYd" user "Package Geometry/Place Bound Top")
		(29 "B.CrtYd" user "Package Geometry/Place Bound Bottom")
		(35 "F.Fab" user "Ref Des/Assembly Top")
		(33 "B.Fab" user "Ref Des/Assembly Bottom")
	)
	(footprint ""
		(layer "F.Cu")
		(at 411.201108 -362.296964)
		(property "Reference" "PR632"
			(at 0 0 0)
			(layer "F.SilkS")
			(hide yes)
			(effects
				(font
					(size 1.27 1.27)
				)
			)
		)
		(property "Value" ""
			(at 0 0 0)
			(layer "F.Fab")
			(effects
				(font
					(size 1.27 1.27)
				)
			)
		)
		(duplicate_pad_numbers_are_jumpers no)
		(fp_line
			(start -0.7874 -0.4064)
			(end 0.7874 -0.4064)
			(stroke
				(width 0.1524)
				(type default)
			)
			(layer "F.SilkS")
		)
		(fp_line
			(start -0.7874 0.4064)
			(end -0.7874 -0.4064)
			(stroke
				(width 0.1524)
				(type default)
			)
			(layer "F.SilkS")
		)
		(fp_line
			(start 0.7874 -0.4064)
			(end 0.7874 0.4064)
			(stroke
				(width 0.1524)
				(type default)
			)
			(layer "F.SilkS")
		)
		(fp_line
			(start 0.7874 0.4064)
			(end -0.7874 0.4064)
			(stroke
				(width 0.1524)
				(type default)
			)
			(layer "F.SilkS")
		)
		(fp_line
			(start -0.67945 -0.305054)
			(end -0.12065 -0.305054)
			(stroke
				(width 0.1)
				(type default)
			)
			(layer "F.Fab")
		)
		(fp_line
			(start -0.67945 0.3048)
			(end -0.67945 -0.305054)
			(stroke
				(width 0.1)
				(type default)
			)
			(layer "F.Fab")
		)
		(fp_line
			(start -0.12065 -0.305054)
			(end -0.12065 -0.2794)
			(stroke
				(width 0.1)
				(type default)
			)
			(layer "F.Fab")
		)
		(fp_line
			(start -0.12065 -0.2794)
			(end 0.12065 -0.2794)
			(stroke
				(width 0.1)
				(type default)
			)
			(layer "F.Fab")
		)
		(fp_line
			(start -0.12065 0.2794)
			(end -0.12065 0.3048)
			(stroke
				(width 0.1)
				(type default)
			)
			(layer "F.Fab")
		)
		(fp_line
			(start -0.12065 0.3048)
			(end -0.67945 0.3048)
			(stroke
				(width 0.1)
				(type default)
			)
			(layer "F.Fab")
		)
		(fp_line
			(start 0.120396 0.2794)
			(end -0.12065 0.2794)
			(stroke
				(width 0.1)
				(type default)
			)
			(layer "F.Fab")
		)
		(fp_line
			(start 0.120396 0.3048)
			(end 0.120396 0.2794)
			(stroke
				(width 0.1)
				(type default)
			)
			(layer "F.Fab")
		)
		(fp_line
			(start 0.12065 -0.3048)
			(end 0.67945 -0.3048)
			(stroke
				(width 0.1)
				(type default)
			)
			(layer "F.Fab")
		)
		(fp_line
			(start 0.12065 -0.2794)
			(end 0.12065 -0.3048)
			(stroke
				(width 0.1)
				(type default)
			)
			(layer "F.Fab")
		)
		(fp_line
			(start 0.67945 -0.3048)
			(end 0.67945 0.3048)
			(stroke
				(width 0.1)
				(type default)
			)
			(layer "F.Fab")
		)
		(fp_line
			(start 0.67945 0.3048)
			(end 0.120396 0.3048)
			(stroke
				(width 0.1)
				(type default)
			)
			(layer "F.Fab")
		)
		(pad "1" smd circle
			(at -0.40005 0)
			(size 0 0)
			(layers "F.Cu" "F.Mask" "F.Paste")
			(net "P3V3")
		)
		(pad "2" smd circle
			(at 0.40005 0)
			(size 0 0)
			(layers "F.Cu" "F.Mask" "F.Paste")
			(net "PVCCFA_EHV_FIVRA_CPU0_PVCC1")
		)
	)
	(footprint ""
		(layer "F.Cu")
		(at 252.961648 -55.177182)
		(property "Reference" "PR3953"
			(at 0 0 0)
			(layer "F.SilkS")
			(hide yes)
			(effects
				(font
					(size 1.27 1.27)
				)
			)
		)
		(property "Value" ""
			(at 0 0 0)
			(layer "F.Fab")
			(effects
				(font
					(size 1.27 1.27)
				)
			)
		)
		(duplicate_pad_numbers_are_jumpers no)
		(fp_line
			(start -0.7874 -0.4064)
			(end 0.7874 -0.4064)
			(stroke
				(width 0.1524)
				(type default)
			)
			(layer "F.SilkS")
		)
		(fp_line
			(start -0.7874 0.4064)
			(end -0.7874 -0.4064)
			(stroke
				(width 0.1524)
				(type default)
			)
			(layer "F.SilkS")
		)
		(fp_line
			(start 0.7874 -0.4064)
			(end 0.7874 0.4064)
			(stroke
				(width 0.1524)
				(type default)
			)
			(layer "F.SilkS")
		)
		(fp_line
			(start 0.7874 0.4064)
			(end -0.7874 0.4064)
			(stroke
				(width 0.1524)
				(type default)
			)
			(layer "F.SilkS")
		)
		(fp_line
			(start -0.67945 -0.305054)
			(end -0.12065 -0.305054)
			(stroke
				(width 0.1)
				(type default)
			)
			(layer "F.Fab")
		)
		(fp_line
			(start -0.67945 0.3048)
			(end -0.67945 -0.305054)
			(stroke
				(width 0.1)
				(type default)
			)
			(layer "F.Fab")
		)
		(fp_line
			(start -0.12065 -0.305054)
			(end -0.12065 -0.2794)
			(stroke
				(width 0.1)
				(type default)
			)
			(layer "F.Fab")
		)
		(fp_line
			(start -0.12065 -0.2794)
			(end 0.12065 -0.2794)
			(stroke
				(width 0.1)
				(type default)
			)
			(layer "F.Fab")
		)
		(fp_line
			(start -0.12065 0.2794)
			(end -0.12065 0.3048)
			(stroke
				(width 0.1)
				(type default)
			)
			(layer "F.Fab")
		)
		(fp_line
			(start -0.12065 0.3048)
			(end -0.67945 0.3048)
			(stroke
				(width 0.1)
				(type default)
			)
			(layer "F.Fab")
		)
		(fp_line
			(start 0.120396 0.2794)
			(end -0.12065 0.2794)
			(stroke
				(width 0.1)
				(type default)
			)
			(layer "F.Fab")
		)
		(fp_line
			(start 0.120396 0.3048)
			(end 0.120396 0.2794)
			(stroke
				(width 0.1)
				(type default)
			)
			(layer "F.Fab")
		)
		(fp_line
			(start 0.12065 -0.3048)
			(end 0.67945 -0.3048)
			(stroke
				(width 0.1)
				(type default)
			)
			(layer "F.Fab")
		)
		(fp_line
			(start 0.12065 -0.2794)
			(end 0.12065 -0.3048)
			(stroke
				(width 0.1)
				(type default)
			)
			(layer "F.Fab")
		)
		(fp_line
			(start 0.67945 -0.3048)
			(end 0.67945 0.3048)
			(stroke
				(width 0.1)
				(type default)
			)
			(layer "F.Fab")
		)
		(fp_line
			(start 0.67945 0.3048)
			(end 0.120396 0.3048)
			(stroke
				(width 0.1)
				(type default)
			)
			(layer "F.Fab")
		)
		(pad "1" smd circle
			(at -0.40005 0)
			(size 0 0)
			(layers "F.Cu" "F.Mask" "F.Paste")
			(net "P12V_AUX")
		)
		(pad "2" smd circle
			(at 0.40005 0)
			(size 0 0)
			(layers "F.Cu" "F.Mask" "F.Paste")
			(net "P12V_E1S_OV_FB_0")
		)
	)
)
